(kicad_pcb
	(version 20241229)
	(generator "pcbnew")
	(generator_version "9.0")
	(general
		(thickness 1.711)
		(legacy_teardrops no)
	)
	(paper "A4")
	(title_block
		(title "Antmicro Baseboard for Jetson AGX Thor")
		(date "2026-02-18")
		(rev "1.1.0")
		(company "Antmicro Ltd")
		(comment 1 "www.antmicro.com")
		(comment 9 "footprints 306-310 of 1170")
	)
	(layers
		(0 "F.Cu" signal)
		(4 "In1.Cu" signal)
		(6 "In2.Cu" signal)
		(8 "In3.Cu" signal)
		(10 "In4.Cu" jumper)
		(12 "In5.Cu" signal)
		(14 "In6.Cu" signal)
		(16 "In7.Cu" signal)
		(18 "In8.Cu" signal)
		(2 "B.Cu" signal)
		(9 "F.Adhes" user "F.Adhesive")
		(11 "B.Adhes" user "B.Adhesive")
		(13 "F.Paste" user)
		(15 "B.Paste" user)
		(5 "F.SilkS" user "F.Silkscreen")
		(7 "B.SilkS" user "B.Silkscreen")
		(1 "F.Mask" user)
		(3 "B.Mask" user)
		(17 "Dwgs.User" user "User.Drawings")
		(19 "Cmts.User" user "User.Comments")
		(21 "Eco1.User" user "User.Eco1")
		(23 "Eco2.User" user "User.Eco2")
		(25 "Edge.Cuts" user)
		(27 "Margin" user)
		(31 "F.CrtYd" user "F.Courtyard")
		(29 "B.CrtYd" user "B.Courtyard")
		(35 "F.Fab" user)
		(33 "B.Fab" user)
	)
	(footprint "antmicro-footprints:R_0402_1005Metric"
		(layer "F.Cu")
		(at 180.859468 139.33 -90)
		(descr "Resistor SMD 0402")
		(tags "resistor SMD 0402")
		(property "Reference" "R13"
			(at -5.83 -2.340532 90)
			(layer "F.SilkS")
			(effects
				(font
					(size 0.7 0.7)
					(thickness 0.15)
				)
				(justify right top)
			)
		)
		(property "Value" "R_499k_0402"
			(at -1.011843 1.772047 90)
			(layer "F.Fab")
			(effects
				(font
					(size 0.7 0.7)
					(thickness 0.15)
				)
				(justify right top)
			)
		)
		(property "Datasheet" "https://www.mouser.com/datasheet/2/54/cr-1858361.pdf"
			(at 0 0 90)
			(layer "F.Fab")
			(hide yes)
			(effects
				(font
					(size 1.27 1.27)
					(thickness 0.15)
				)
			)
		)
		(property "Description" "SMD Chip Resistor, 499 kohm, ± 1%, 63 mW, 0402 [1005 Metric], Thick Film, General Purpose"
			(at 0 0 90)
			(layer "F.Fab")
			(hide yes)
			(effects
				(font
					(size 1.27 1.27)
					(thickness 0.15)
				)
			)
		)
		(property "MPN" "CR0402-FX-4993GLF"
			(at 0 0 270)
			(unlocked yes)
			(layer "F.Fab")
			(hide yes)
			(effects
				(font
					(size 1 1)
					(thickness 0.15)
				)
			)
		)
		(property "Manufacturer" "Bourns"
			(at 0 0 270)
			(unlocked yes)
			(layer "F.Fab")
			(hide yes)
			(effects
				(font
					(size 1 1)
					(thickness 0.15)
				)
			)
		)
		(property "License" "Apache-2.0"
			(at 0 0 270)
			(unlocked yes)
			(layer "F.Fab")
			(hide yes)
			(effects
				(font
					(size 1 1)
					(thickness 0.15)
				)
			)
		)
		(property "Author" "Antmicro"
			(at 0 0 270)
			(unlocked yes)
			(layer "F.Fab")
			(hide yes)
			(effects
				(font
					(size 1 1)
					(thickness 0.15)
				)
			)
		)
		(property "Val" "499k"
			(at 0 0 270)
			(unlocked yes)
			(layer "F.Fab")
			(hide yes)
			(effects
				(font
					(size 1 1)
					(thickness 0.15)
				)
			)
		)
		(property "Tolerance" "1%"
			(at 0 0 270)
			(unlocked yes)
			(layer "F.Fab")
			(hide yes)
			(effects
				(font
					(size 1 1)
					(thickness 0.15)
				)
			)
		)
		(sheetname "/DCDC/")
		(sheetfile "dcdc.kicad_sch")
		(attr smd)
		(fp_rect
			(start -0.925 -0.47)
			(end 0.925 0.47)
			(stroke
				(width 0.05)
				(type default)
			)
			(fill no)
			(layer "F.CrtYd")
		)
		(fp_rect
			(start -0.5 -0.25)
			(end 0.5 0.25)
			(stroke
				(width 0.15)
				(type solid)
			)
			(fill no)
			(layer "F.Fab")
		)
		(fp_text user "License: Apache-2.0"
			(at -0.95 5.169 90)
			(layer "F.Fab")
			(effects
				(font
					(size 0.7 0.7)
					(thickness 0.15)
				)
				(justify right top)
			)
		)
		(fp_text user "Author: Antmicro"
			(at -0.95 4.169 90)
			(layer "F.Fab")
			(effects
				(font
					(size 0.7 0.7)
					(thickness 0.15)
				)
				(justify right top)
			)
		)
		(fp_text user "${REFERENCE}"
			(at -0.95 3.168 90)
			(layer "F.Fab")
			(effects
				(font
					(size 0.7 0.7)
					(thickness 0.15)
				)
				(justify right top)
			)
		)
		(pad "1" smd roundrect
			(at -0.48 0 270)
			(size 0.59 0.64)
			(layers "F.Cu" "F.Mask" "F.Paste")
			(roundrect_rratio 0.25)
			(net 1 "GND")
			(pintype "passive")
		)
		(pad "2" smd roundrect
			(at 0.48 0 270)
			(size 0.59 0.64)
			(layers "F.Cu" "F.Mask" "F.Paste")
			(roundrect_rratio 0.25)
			(net 1204 "/DCDC/12V_MODE1")
			(pintype "passive")
		)
	)
	(footprint "antmicro-footprints:R_0402_1005Metric"
		(layer "F.Cu")
		(at 196.35 85.92 -90)
		(descr "Resistor SMD 0402")
		(tags "resistor SMD 0402")
		(property "Reference" "R108"
			(at -1.71 1.46 90)
			(layer "F.SilkS")
			(effects
				(font
					(size 0.7 0.7)
					(thickness 0.15)
				)
				(justify right top)
			)
		)
		(property "Value" "R_200R_0402"
			(at -1.011843 1.772047 90)
			(layer "F.Fab")
			(effects
				(font
					(size 0.7 0.7)
					(thickness 0.15)
				)
				(justify right top)
			)
		)
		(property "Datasheet" "https://www.bourns.com/docs/product-datasheets/cr.pdf"
			(at 0 0 90)
			(layer "F.Fab")
			(hide yes)
			(effects
				(font
					(size 1.27 1.27)
					(thickness 0.15)
				)
			)
		)
		(property "Description" "SMD Chip Resistor, 200 ohm, ± 1%, 62.5 mW, 0402 [1005 Metric], Thick Film, General Purpose"
			(at 0 0 90)
			(layer "F.Fab")
			(hide yes)
			(effects
				(font
					(size 1.27 1.27)
					(thickness 0.15)
				)
			)
		)
		(property "Manufacturer" "Bourns"
			(at 0 0 270)
			(unlocked yes)
			(layer "F.Fab")
			(hide yes)
			(effects
				(font
					(size 1 1)
					(thickness 0.15)
				)
			)
		)
		(property "MPN" "CR0402-FX-2000GLF"
			(at 0 0 270)
			(unlocked yes)
			(layer "F.Fab")
			(hide yes)
			(effects
				(font
					(size 1 1)
					(thickness 0.15)
				)
			)
		)
		(property "Val" "200R"
			(at 0 0 270)
			(unlocked yes)
			(layer "F.Fab")
			(hide yes)
			(effects
				(font
					(size 1 1)
					(thickness 0.15)
				)
			)
		)
		(property "License" "Apache-2.0"
			(at 0 0 270)
			(unlocked yes)
			(layer "F.Fab")
			(hide yes)
			(effects
				(font
					(size 1 1)
					(thickness 0.15)
				)
			)
		)
		(property "Author" "Antmicro"
			(at 0 0 270)
			(unlocked yes)
			(layer "F.Fab")
			(hide yes)
			(effects
				(font
					(size 1 1)
					(thickness 0.15)
				)
			)
		)
		(property "Tolerance" "1%"
			(at 0 0 270)
			(unlocked yes)
			(layer "F.Fab")
			(hide yes)
			(effects
				(font
					(size 1 1)
					(thickness 0.15)
				)
			)
		)
		(sheetname "/USB Debug, PD/")
		(sheetfile "usb_debug_pd.kicad_sch")
		(attr smd)
		(fp_rect
			(start -0.925 -0.47)
			(end 0.925 0.47)
			(stroke
				(width 0.05)
				(type default)
			)
			(fill no)
			(layer "F.CrtYd")
		)
		(fp_rect
			(start -0.5 -0.25)
			(end 0.5 0.25)
			(stroke
				(width 0.15)
				(type solid)
			)
			(fill no)
			(layer "F.Fab")
		)
		(fp_text user "License: Apache-2.0"
			(at -0.95 5.169 90)
			(layer "F.Fab")
			(effects
				(font
					(size 0.7 0.7)
					(thickness 0.15)
				)
				(justify right top)
			)
		)
		(fp_text user "${REFERENCE}"
			(at -0.95 3.168 90)
			(layer "F.Fab")
			(effects
				(font
					(size 0.7 0.7)
					(thickness 0.15)
				)
				(justify right top)
			)
		)
		(fp_text user "Author: Antmicro"
			(at -0.95 4.169 90)
			(layer "F.Fab")
			(effects
				(font
					(size 0.7 0.7)
					(thickness 0.15)
				)
				(justify right top)
			)
		)
		(pad "1" smd roundrect
			(at -0.48 0 270)
			(size 0.59 0.64)
			(layers "F.Cu" "F.Mask" "F.Paste")
			(roundrect_rratio 0.25)
			(net 951 "/USB Debug, PD/PDC_GPIO14")
			(pintype "passive")
		)
		(pad "2" smd roundrect
			(at 0.48 0 270)
			(size 0.59 0.64)
			(layers "F.Cu" "F.Mask" "F.Paste")
			(roundrect_rratio 0.25)
			(net 533 "Net-(D18-A)")
			(pintype "passive")
		)
	)
	(footprint "antmicro-footprints:C_0402_1005Metric"
		(layer "F.Cu")
		(at 215.524132 84.282 -90)
		(descr "Capacitor SMD 0402")
		(tags "capacitor SMD 0402")
		(property "Reference" "C129"
			(at -3.682 0.324132 90)
			(layer "F.SilkS")
			(effects
				(font
					(size 0.7 0.7)
					(thickness 0.15)
				)
				(justify right top)
			)
		)
		(property "Value" "C_100n_0402"
			(at -1.022927 2.155213 90)
			(layer "F.Fab")
			(effects
				(font
					(size 0.7 0.7)
					(thickness 0.15)
				)
				(justify right top)
			)
		)
		(property "Datasheet" "https://www.murata.com/products/productdetail?partno=GRM155R61H104KE14%23"
			(at 0 0 90)
			(layer "F.Fab")
			(hide yes)
			(effects
				(font
					(size 1.27 1.27)
					(thickness 0.15)
				)
			)
		)
		(property "Description" "SMD Multilayer Ceramic Capacitor, 0.1 µF, 50 V, 0402 [1005 Metric], ± 10%, X5R, GRM Series"
			(at 0 0 90)
			(layer "F.Fab")
			(hide yes)
			(effects
				(font
					(size 1.27 1.27)
					(thickness 0.15)
				)
			)
		)
		(property "Manufacturer" "Murata"
			(at 0 0 270)
			(unlocked yes)
			(layer "F.Fab")
			(hide yes)
			(effects
				(font
					(size 1 1)
					(thickness 0.15)
				)
			)
		)
		(property "MPN" "GRM155R61H104KE14D"
			(at 0 0 270)
			(unlocked yes)
			(layer "F.Fab")
			(hide yes)
			(effects
				(font
					(size 1 1)
					(thickness 0.15)
				)
			)
		)
		(property "Val" "100n"
			(at 0 0 270)
			(unlocked yes)
			(layer "F.Fab")
			(hide yes)
			(effects
				(font
					(size 1 1)
					(thickness 0.15)
				)
			)
		)
		(property "License" "Apache-2.0"
			(at 0 0 270)
			(unlocked yes)
			(layer "F.Fab")
			(hide yes)
			(effects
				(font
					(size 1 1)
					(thickness 0.15)
				)
			)
		)
		(property "Author" "Antmicro"
			(at 0 0 270)
			(unlocked yes)
			(layer "F.Fab")
			(hide yes)
			(effects
				(font
					(size 1 1)
					(thickness 0.15)
				)
			)
		)
		(property "Voltage" "50V"
			(at 0 0 270)
			(unlocked yes)
			(layer "F.Fab")
			(hide yes)
			(effects
				(font
					(size 1 1)
					(thickness 0.15)
				)
			)
		)
		(property "Dielectric" "X5R"
			(at 0 0 270)
			(unlocked yes)
			(layer "F.Fab")
			(hide yes)
			(effects
				(font
					(size 1 1)
					(thickness 0.15)
				)
			)
		)
		(sheetname "/USB DP Alt mode/")
		(sheetfile "usb_dp.kicad_sch")
		(attr smd)
		(fp_rect
			(start -0.925 -0.47)
			(end 0.925 0.47)
			(stroke
				(width 0.05)
				(type default)
			)
			(fill no)
			(layer "F.CrtYd")
		)
		(fp_line
			(start -0.494 0.248)
			(end -0.494 -0.25)
			(stroke
				(width 0.15)
				(type solid)
			)
			(layer "F.Fab")
		)
		(fp_line
			(start 0.504 0.248)
			(end -0.494 0.248)
			(stroke
				(width 0.15)
				(type solid)
			)
			(layer "F.Fab")
		)
		(fp_line
			(start -0.494 -0.25)
			(end 0.504 -0.25)
			(stroke
				(width 0.15)
				(type solid)
			)
			(layer "F.Fab")
		)
		(fp_line
			(start 0.504 -0.25)
			(end 0.504 0.248)
			(stroke
				(width 0.15)
				(type solid)
			)
			(layer "F.Fab")
		)
		(fp_text user "License: Apache-2.0"
			(at -0.939 5.799 90)
			(layer "F.Fab")
			(effects
				(font
					(size 0.7 0.7)
					(thickness 0.15)
				)
				(justify right top)
			)
		)
		(fp_text user "${REFERENCE}"
			(at -0.939 4.599 90)
			(layer "F.Fab")
			(effects
				(font
					(size 0.7 0.7)
					(thickness 0.15)
				)
				(justify right top)
			)
		)
		(fp_text user "Author: Antmicro"
			(at -0.939 3.399 90)
			(layer "F.Fab")
			(effects
				(font
					(size 0.7 0.7)
					(thickness 0.15)
				)
				(justify right top)
			)
		)
		(pad "1" smd roundrect
			(at -0.48 0 270)
			(size 0.59 0.64)
			(layers "F.Cu" "F.Mask" "F.Paste")
			(roundrect_rratio 0.25)
			(net 324 "/SoM_IO2/USBSS1.RX-")
			(pintype "passive")
		)
		(pad "2" smd roundrect
			(at 0.48 0 270)
			(size 0.59 0.64)
			(layers "F.Cu" "F.Mask" "F.Paste")
			(roundrect_rratio 0.25)
			(net 322 "/USB DP Alt mode/USBSS1_RX_C_N")
			(pintype "passive")
		)
	)
	(footprint "antmicro-footprints:C_0402_1005Metric"
		(layer "F.Cu")
		(at 89.1 96.9)
		(descr "Capacitor SMD 0402")
		(tags "capacitor SMD 0402")
		(property "Reference" "C336"
			(at -3.82 0.45 0)
			(layer "F.SilkS")
			(effects
				(font
					(size 0.7 0.7)
					(thickness 0.15)
				)
				(justify left bottom)
			)
		)
		(property "Value" "C_100n_0402"
			(at -1.022927 2.155213 0)
			(layer "F.Fab")
			(effects
				(font
					(size 0.7 0.7)
					(thickness 0.15)
				)
				(justify left bottom)
			)
		)
		(property "Datasheet" "https://www.murata.com/products/productdetail?partno=GRM155R61H104KE14%23"
			(at 0 0 0)
			(layer "F.Fab")
			(hide yes)
			(effects
				(font
					(size 1.27 1.27)
					(thickness 0.15)
				)
			)
		)
		(property "Description" "SMD Multilayer Ceramic Capacitor, 0.1 µF, 50 V, 0402 [1005 Metric], ± 10%, X5R, GRM Series"
			(at 0 0 0)
			(layer "F.Fab")
			(hide yes)
			(effects
				(font
					(size 1.27 1.27)
					(thickness 0.15)
				)
			)
		)
		(property "Manufacturer" "Murata"
			(at 0 0 0)
			(unlocked yes)
			(layer "F.Fab")
			(hide yes)
			(effects
				(font
					(size 1 1)
					(thickness 0.15)
				)
			)
		)
		(property "MPN" "GRM155R61H104KE14D"
			(at 0 0 0)
			(unlocked yes)
			(layer "F.Fab")
			(hide yes)
			(effects
				(font
					(size 1 1)
					(thickness 0.15)
				)
			)
		)
		(property "Val" "100n"
			(at 0 0 0)
			(unlocked yes)
			(layer "F.Fab")
			(hide yes)
			(effects
				(font
					(size 1 1)
					(thickness 0.15)
				)
			)
		)
		(property "License" "Apache-2.0"
			(at 0 0 0)
			(unlocked yes)
			(layer "F.Fab")
			(hide yes)
			(effects
				(font
					(size 1 1)
					(thickness 0.15)
				)
			)
		)
		(property "Author" "Antmicro"
			(at 0 0 0)
			(unlocked yes)
			(layer "F.Fab")
			(hide yes)
			(effects
				(font
					(size 1 1)
					(thickness 0.15)
				)
			)
		)
		(property "Voltage" "50V"
			(at 0 0 0)
			(unlocked yes)
			(layer "F.Fab")
			(hide yes)
			(effects
				(font
					(size 1 1)
					(thickness 0.15)
				)
			)
		)
		(property "Dielectric" "X5R"
			(at 0 0 0)
			(unlocked yes)
			(layer "F.Fab")
			(hide yes)
			(effects
				(font
					(size 1 1)
					(thickness 0.15)
				)
			)
		)
		(sheetname "/SoM_IO2/")
		(sheetfile "som_io2.kicad_sch")
		(attr smd)
		(fp_rect
			(start -0.925 -0.47)
			(end 0.925 0.47)
			(stroke
				(width 0.05)
				(type default)
			)
			(fill no)
			(layer "F.CrtYd")
		)
		(fp_line
			(start -0.494 -0.25)
			(end 0.504 -0.25)
			(stroke
				(width 0.15)
				(type solid)
			)
			(layer "F.Fab")
		)
		(fp_line
			(start -0.494 0.248)
			(end -0.494 -0.25)
			(stroke
				(width 0.15)
				(type solid)
			)
			(layer "F.Fab")
		)
		(fp_line
			(start 0.504 -0.25)
			(end 0.504 0.248)
			(stroke
				(width 0.15)
				(type solid)
			)
			(layer "F.Fab")
		)
		(fp_line
			(start 0.504 0.248)
			(end -0.494 0.248)
			(stroke
				(width 0.15)
				(type solid)
			)
			(layer "F.Fab")
		)
		(fp_text user "${REFERENCE}"
			(at -0.939 4.599 0)
			(layer "F.Fab")
			(effects
				(font
					(size 0.7 0.7)
					(thickness 0.15)
				)
				(justify left bottom)
			)
		)
		(fp_text user "License: Apache-2.0"
			(at -0.939 5.799 0)
			(layer "F.Fab")
			(effects
				(font
					(size 0.7 0.7)
					(thickness 0.15)
				)
				(justify left bottom)
			)
		)
		(fp_text user "Author: Antmicro"
			(at -0.939 3.399 0)
			(layer "F.Fab")
			(effects
				(font
					(size 0.7 0.7)
					(thickness 0.15)
				)
				(justify left bottom)
			)
		)
		(pad "1" smd roundrect
			(at -0.48 0)
			(size 0.59 0.64)
			(layers "F.Cu" "F.Mask" "F.Paste")
			(roundrect_rratio 0.25)
			(net 756 "/Expansion connector/DP2.TX2+")
			(pintype "passive")
		)
		(pad "2" smd roundrect
			(at 0.48 0)
			(size 0.59 0.64)
			(layers "F.Cu" "F.Mask" "F.Paste")
			(roundrect_rratio 0.25)
			(net 1256 "/SoM_IO2/DP2.TX2_C+")
			(pintype "passive")
		)
	)
	(footprint "antmicro-footprints:TP_SMD_0.75mm"
		(layer "F.Cu")
		(at 69.279 61.981 90)
		(property "Reference" "TP22"
			(at 0.41 3.21 0)
			(layer "F.SilkS")
			(effects
				(font
					(size 0.7 0.7)
					(thickness 0.15)
				)
				(justify right top)
			)
		)
		(property "Value" "TP_0.75mm_SMD"
			(at 0 1.2 90)
			(layer "F.Fab")
			(effects
				(font
					(size 0.7 0.7)
					(thickness 0.15)
				)
				(justify left bottom)
			)
		)
		(property "Description" "SMT test point"
			(at 0 0 90)
			(layer "F.Fab")
			(hide yes)
			(effects
				(font
					(size 1.27 1.27)
					(thickness 0.15)
				)
			)
		)
		(property "MPN" ""
			(at 0 0 90)
			(unlocked yes)
			(layer "F.Fab")
			(hide yes)
			(effects
				(font
					(size 1 1)
					(thickness 0.15)
				)
			)
		)
		(property "Manufacturer" ""
			(at 0 0 90)
			(unlocked yes)
			(layer "F.Fab")
			(hide yes)
			(effects
				(font
					(size 1 1)
					(thickness 0.15)
				)
			)
		)
		(property "Author" "Antmicro"
			(at 0 0 90)
			(unlocked yes)
			(layer "F.Fab")
			(hide yes)
			(effects
				(font
					(size 1 1)
					(thickness 0.15)
				)
			)
		)
		(property "License" "Apache-2.0"
			(at 0 0 90)
			(unlocked yes)
			(layer "F.Fab")
			(hide yes)
			(effects
				(font
					(size 1 1)
					(thickness 0.15)
				)
			)
		)
		(sheetname "/CSI/")
		(sheetfile "csi.kicad_sch")
		(attr exclude_from_pos_files exclude_from_bom)
		(fp_circle
			(center 0 0)
			(end 0.475 0)
			(stroke
				(width 0.05)
				(type default)
			)
			(fill no)
			(layer "F.CrtYd")
		)
		(fp_text user "${REFERENCE}"
			(at -0.4 2.7 90)
			(layer "F.Fab")
			(effects
				(font
					(size 0.7 0.7)
					(thickness 0.15)
				)
				(justify left bottom)
			)
		)
		(fp_text user "Author: Antmicro"
			(at -0.4 3.901 90)
			(layer "F.Fab")
			(effects
				(font
					(size 0.7 0.7)
					(thickness 0.15)
				)
				(justify left bottom)
			)
		)
		(fp_text user "License: Apache-2.0"
			(at -0.4 5.101 90)
			(layer "F.Fab")
			(effects
				(font
					(size 0.7 0.7)
					(thickness 0.15)
				)
				(justify left bottom)
			)
		)
		(pad "1" smd circle
			(at 0 0 90)
			(size 0.75 0.75)
			(layers "F.Cu" "F.Mask")
			(net 1046 "/CSI/MUX_I2C_4_SCL")
			(pinfunction "1")
			(pintype "passive")
		)
	)
)
